(kicad_pcb
	(version 20260206)
	(generator "pcbnew")
	(generator_version "10.0")
	(general
		(thickness 1.6)
		(legacy_teardrops no)
	)
	(paper "A4")
	(title_block
		(title "Wiwynn_Tioga_Pass_MB.brd")
		(comment 1 "Tioga Pass / footprints 514-520 of 4770")
	)
	(layers
		(0 "F.Cu" signal "TOP")
		(4 "In1.Cu" signal "L2GND")
		(6 "In2.Cu" signal "L3")
		(8 "In3.Cu" signal "L4GND")
		(10 "In4.Cu" signal "L5")
		(12 "In5.Cu" signal "L6GND")
		(14 "In6.Cu" signal "L7VCC")
		(16 "In7.Cu" signal "L8VCC")
		(18 "In8.Cu" signal "L9GND")
		(20 "In9.Cu" signal "L10")
		(22 "In10.Cu" signal "L11GND")
		(24 "In11.Cu" signal "L12")
		(26 "In12.Cu" signal "L13GND")
		(2 "B.Cu" signal "BOTTOM")
		(9 "F.Adhes" user "F.Adhesive")
		(11 "B.Adhes" user "B.Adhesive")
		(13 "F.Paste" user "Package Geometry/Pastemask Top")
		(15 "B.Paste" user "Package Geometry/Pastemask Bottom")
		(5 "F.SilkS" user "Ref Des/Silkscreen Top")
		(7 "B.SilkS" user "Ref Des/Silkscreen Bottom")
		(1 "F.Mask" user "Board Geometry/Soldermask Top")
		(3 "B.Mask" user "Board Geometry/Soldermask Bottom")
		(17 "Dwgs.User" user "User.Drawings")
		(19 "Cmts.User" user "User.Comments")
		(21 "Eco1.User" user "User.Eco1")
		(23 "Eco2.User" user "User.Eco2")
		(25 "Edge.Cuts" user "Board Geometry/Outline")
		(27 "Margin" user)
		(31 "F.CrtYd" user "Package Geometry/Place Bound Top")
		(29 "B.CrtYd" user "Package Geometry/Place Bound Bottom")
		(35 "F.Fab" user "Ref Des/Assembly Top")
		(33 "B.Fab" user "Ref Des/Assembly Bottom")
	)
	(footprint ""
		(layer "F.Cu")
		(at 214.503 -70.358)
		(property "Reference" "C4D34"
			(at 0 0 0)
			(layer "F.SilkS")
			(hide yes)
			(effects
				(font
					(size 1.27 1.27)
				)
			)
		)
		(property "Value" ""
			(at 0 0 0)
			(layer "F.Fab")
			(effects
				(font
					(size 1.27 1.27)
				)
			)
		)
		(duplicate_pad_numbers_are_jumpers no)
		(fp_poly
			(pts
				(xy -0.4953 -0.2032) (xy 0.4953 -0.2032) (xy 0.4953 1.6002) (xy -0.4953 1.6002)
			)
			(stroke
				(width 0)
				(type default)
			)
			(fill no)
			(layer "F.CrtYd")
		)
		(fp_line
			(start -0.4953 -0.2032)
			(end 0.4953 -0.2032)
			(stroke
				(width 0.1)
				(type default)
			)
			(layer "F.Fab")
		)
		(fp_line
			(start -0.4953 1.6002)
			(end -0.4953 -0.2032)
			(stroke
				(width 0.1)
				(type default)
			)
			(layer "F.Fab")
		)
		(fp_line
			(start 0.4953 -0.2032)
			(end 0.4953 1.6002)
			(stroke
				(width 0.1)
				(type default)
			)
			(layer "F.Fab")
		)
		(fp_line
			(start 0.4953 1.6002)
			(end -0.4953 1.6002)
			(stroke
				(width 0.1)
				(type default)
			)
			(layer "F.Fab")
		)
		(pad "1" smd rect
			(at 0 0)
			(size 0.762 0.889)
			(layers "F.Cu" "F.Mask" "F.Paste")
			(net "PVCCIN_CPU0")
		)
		(pad "2" smd rect
			(at 0 1.397)
			(size 0.762 0.889)
			(layers "F.Cu" "F.Mask" "F.Paste")
			(net "GND")
		)
		(zone
			(layer "F.Cu")
			(hatch none 0.5)
			(connect_pads
				(clearance 0)
			)
			(min_thickness 0.25)
			(keepout
				(tracks not_allowed)
				(vias allowed)
				(pads allowed)
				(copperpour not_allowed)
				(footprints allowed)
			)
			(placement
				(enabled no)
				(sheetname "")
			)
			(fill
				(thermal_gap 0.5)
				(thermal_bridge_width 0.5)
				(island_removal_mode 0)
			)
			(polygon
				(pts
					(xy 214.122 -69.9135) (xy 214.884 -69.9135) (xy 214.884 -69.4055) (xy 214.122 -69.4055)
				)
			)
		)
	)
	(footprint ""
		(layer "F.Cu")
		(at 351.913444 -146.90471 90)
		(property "Reference" "R7A21"
			(at 0 0 90)
			(layer "F.SilkS")
			(hide yes)
			(effects
				(font
					(size 1.27 1.27)
				)
			)
		)
		(property "Value" ""
			(at 0 0 90)
			(layer "F.Fab")
			(effects
				(font
					(size 1.27 1.27)
				)
			)
		)
		(duplicate_pad_numbers_are_jumpers no)
		(fp_poly
			(pts
				(xy -0.2794 -0.1016) (xy 0.2794 -0.1016) (xy 0.2794 0.9906) (xy -0.2794 0.9906)
			)
			(stroke
				(width 0)
				(type default)
			)
			(fill no)
			(layer "F.CrtYd")
		)
		(fp_line
			(start 0.2794 -0.1016)
			(end -0.2794 -0.1016)
			(stroke
				(width 0.1)
				(type default)
			)
			(layer "F.Fab")
		)
		(fp_line
			(start -0.2794 -0.1016)
			(end -0.2794 0.9906)
			(stroke
				(width 0.1)
				(type default)
			)
			(layer "F.Fab")
		)
		(fp_line
			(start 0.2794 0.9906)
			(end 0.2794 -0.1016)
			(stroke
				(width 0.1)
				(type default)
			)
			(layer "F.Fab")
		)
		(fp_line
			(start -0.2794 0.9906)
			(end 0.2794 0.9906)
			(stroke
				(width 0.1)
				(type default)
			)
			(layer "F.Fab")
		)
		(pad "1" smd rect
			(at 0 0 90)
			(size 0.508 0.508)
			(layers "F.Cu" "F.Mask" "F.Paste")
			(net "VR_PVDDQ_DEF_PH2_OCSET")
		)
		(pad "2" smd rect
			(at 0 0.889 90)
			(size 0.508 0.508)
			(layers "F.Cu" "F.Mask" "F.Paste")
			(net "GND")
		)
		(zone
			(layer "F.Cu")
			(hatch none 0.5)
			(connect_pads
				(clearance 0)
			)
			(min_thickness 0.25)
			(keepout
				(tracks allowed)
				(vias not_allowed)
				(pads allowed)
				(copperpour not_allowed)
				(footprints allowed)
			)
			(placement
				(enabled no)
				(sheetname "")
			)
			(fill
				(thermal_gap 0.5)
				(thermal_bridge_width 0.5)
				(island_removal_mode 0)
			)
			(polygon
				(pts
					(xy 352.167444 -146.65071) (xy 352.167444 -147.15871) (xy 352.548444 -147.15871) (xy 352.548444 -146.65071)
				)
			)
		)
		(zone
			(layer "F.Cu")
			(hatch none 0.5)
			(connect_pads
				(clearance 0)
			)
			(min_thickness 0.25)
			(keepout
				(tracks not_allowed)
				(vias allowed)
				(pads allowed)
				(copperpour not_allowed)
				(footprints allowed)
			)
			(placement
				(enabled no)
				(sheetname "")
			)
			(fill
				(thermal_gap 0.5)
				(thermal_bridge_width 0.5)
				(island_removal_mode 0)
			)
			(polygon
				(pts
					(xy 352.548444 -146.65071) (xy 352.548444 -147.15871) (xy 352.167444 -147.15871) (xy 352.167444 -146.65071)
				)
			)
		)
	)
	(footprint ""
		(layer "F.Cu")
		(at 433.0446 -16.832072 180)
		(property "Reference" "R6W47"
			(at -0.8382 -0.67818 180)
			(unlocked yes)
			(layer "F.SilkS")
			(effects
				(font
					(size 0.4064 0.254)
					(thickness 0.1524)
				)
				(justify left)
			)
		)
		(property "Value" ""
			(at 0 0 180)
			(layer "F.Fab")
			(effects
				(font
					(size 1.27 1.27)
				)
			)
		)
		(duplicate_pad_numbers_are_jumpers no)
		(fp_poly
			(pts
				(xy -0.2794 -0.1016) (xy 0.2794 -0.1016) (xy 0.2794 0.9906) (xy -0.2794 0.9906)
			)
			(stroke
				(width 0)
				(type default)
			)
			(fill no)
			(layer "F.CrtYd")
		)
		(fp_line
			(start 0.2794 0.9906)
			(end 0.2794 -0.1016)
			(stroke
				(width 0.1)
				(type default)
			)
			(layer "F.Fab")
		)
		(fp_line
			(start 0.2794 -0.1016)
			(end -0.2794 -0.1016)
			(stroke
				(width 0.1)
				(type default)
			)
			(layer "F.Fab")
		)
		(fp_line
			(start -0.2794 0.9906)
			(end 0.2794 0.9906)
			(stroke
				(width 0.1)
				(type default)
			)
			(layer "F.Fab")
		)
		(fp_line
			(start -0.2794 -0.1016)
			(end -0.2794 0.9906)
			(stroke
				(width 0.1)
				(type default)
			)
			(layer "F.Fab")
		)
		(pad "1" smd rect
			(at 0 0 180)
			(size 0.508 0.508)
			(layers "F.Cu" "F.Mask" "F.Paste")
			(net "PCA9554_A0")
		)
		(pad "2" smd rect
			(at 0 0.889 180)
			(size 0.508 0.508)
			(layers "F.Cu" "F.Mask" "F.Paste")
			(net "GND")
		)
		(zone
			(layer "F.Cu")
			(hatch none 0.5)
			(connect_pads
				(clearance 0)
			)
			(min_thickness 0.25)
			(keepout
				(tracks not_allowed)
				(vias allowed)
				(pads allowed)
				(copperpour not_allowed)
				(footprints allowed)
			)
			(placement
				(enabled no)
				(sheetname "")
			)
			(fill
				(thermal_gap 0.5)
				(thermal_bridge_width 0.5)
				(island_removal_mode 0)
			)
			(polygon
				(pts
					(xy 433.2986 -17.467072) (xy 432.7906 -17.467072) (xy 432.7906 -17.086072) (xy 433.2986 -17.086072)
				)
			)
		)
		(zone
			(layer "F.Cu")
			(hatch none 0.5)
			(connect_pads
				(clearance 0)
			)
			(min_thickness 0.25)
			(keepout
				(tracks allowed)
				(vias not_allowed)
				(pads allowed)
				(copperpour not_allowed)
				(footprints allowed)
			)
			(placement
				(enabled no)
				(sheetname "")
			)
			(fill
				(thermal_gap 0.5)
				(thermal_bridge_width 0.5)
				(island_removal_mode 0)
			)
			(polygon
				(pts
					(xy 433.2986 -17.086072) (xy 432.7906 -17.086072) (xy 432.7906 -17.467072) (xy 433.2986 -17.467072)
				)
			)
		)
	)
	(footprint ""
		(layer "F.Cu")
		(at 209.296 -51.382168)
		(property "Reference" "R5P1"
			(at 0 0 0)
			(layer "F.SilkS")
			(hide yes)
			(effects
				(font
					(size 1.27 1.27)
				)
			)
		)
		(property "Value" ""
			(at 0 0 0)
			(layer "F.Fab")
			(effects
				(font
					(size 1.27 1.27)
				)
			)
		)
		(duplicate_pad_numbers_are_jumpers no)
		(fp_poly
			(pts
				(xy -0.4953 -0.2032) (xy 0.4953 -0.2032) (xy 0.4953 1.6002) (xy -0.4953 1.6002)
			)
			(stroke
				(width 0)
				(type default)
			)
			(fill no)
			(layer "F.CrtYd")
		)
		(fp_line
			(start -0.4953 -0.2032)
			(end 0.4953 -0.2032)
			(stroke
				(width 0.1)
				(type default)
			)
			(layer "F.Fab")
		)
		(fp_line
			(start -0.4953 1.6002)
			(end -0.4953 -0.2032)
			(stroke
				(width 0.1)
				(type default)
			)
			(layer "F.Fab")
		)
		(fp_line
			(start 0.4953 -0.2032)
			(end 0.4953 1.6002)
			(stroke
				(width 0.1)
				(type default)
			)
			(layer "F.Fab")
		)
		(fp_line
			(start 0.4953 1.6002)
			(end -0.4953 1.6002)
			(stroke
				(width 0.1)
				(type default)
			)
			(layer "F.Fab")
		)
		(pad "1" smd rect
			(at 0 0)
			(size 0.762 0.889)
			(layers "F.Cu" "F.Mask" "F.Paste")
			(net "PVCCIN_CPU0")
		)
		(pad "2" smd rect
			(at 0 1.397)
			(size 0.762 0.889)
			(layers "F.Cu" "F.Mask" "F.Paste")
			(net "VSENSE_VCCINR2PMAX_CPU0")
		)
		(zone
			(layer "F.Cu")
			(hatch none 0.5)
			(connect_pads
				(clearance 0)
			)
			(min_thickness 0.25)
			(keepout
				(tracks not_allowed)
				(vias allowed)
				(pads allowed)
				(copperpour not_allowed)
				(footprints allowed)
			)
			(placement
				(enabled no)
				(sheetname "")
			)
			(fill
				(thermal_gap 0.5)
				(thermal_bridge_width 0.5)
				(island_removal_mode 0)
			)
			(polygon
				(pts
					(xy 208.915 -50.429668) (xy 209.677 -50.429668) (xy 209.677 -50.937668) (xy 208.915 -50.937668)
				)
			)
		)
		(zone
			(layer "F.Cu")
			(hatch none 0.5)
			(connect_pads
				(clearance 0)
			)
			(min_thickness 0.25)
			(keepout
				(tracks allowed)
				(vias not_allowed)
				(pads allowed)
				(copperpour not_allowed)
				(footprints allowed)
			)
			(placement
				(enabled no)
				(sheetname "")
			)
			(fill
				(thermal_gap 0.5)
				(thermal_bridge_width 0.5)
				(island_removal_mode 0)
			)
			(polygon
				(pts
					(xy 209.677 -50.429668) (xy 209.677 -50.937668) (xy 208.915 -50.937668) (xy 208.915 -50.429668)
				)
			)
		)
	)
	(footprint ""
		(layer "F.Cu")
		(at 439.160412 -153.572718 90)
		(property "Reference" "FB25W2"
			(at 0 0 90)
			(layer "F.SilkS")
			(hide yes)
			(effects
				(font
					(size 1.27 1.27)
				)
			)
		)
		(property "Value" "*"
			(at -0.0127 -7.01675 90)
			(unlocked yes)
			(layer "F.Fab")
			(hide yes)
			(effects
				(font
					(size 0.889 0.889)
					(thickness 0.1524)
				)
			)
		)
		(property "Device Type" "BLM15AG121SN-1GP_DISCRET-G-BLMA"
			(at -0.0127 -8.54075 90)
			(unlocked yes)
			(layer "F.Fab")
			(hide yes)
			(effects
				(font
					(size 0.889 0.889)
					(thickness 0.1524)
				)
			)
		)
		(duplicate_pad_numbers_are_jumpers no)
		(fp_line
			(start 0.508 -0.9398)
			(end -0.508 -0.9398)
			(stroke
				(width 0.1524)
				(type default)
			)
			(layer "F.SilkS")
		)
		(fp_line
			(start -0.508 -0.9398)
			(end -0.508 0.9398)
			(stroke
				(width 0.1524)
				(type default)
			)
			(layer "F.SilkS")
		)
		(fp_line
			(start -0.508 0.9398)
			(end -0.508 0.8636)
			(stroke
				(width 0.1524)
				(type default)
			)
			(layer "F.SilkS")
		)
		(fp_rect
			(start -0.508 0.9398)
			(end 0.508 -0.9398)
			(stroke
				(width 0)
				(type default)
			)
			(fill no)
			(layer "F.CrtYd")
		)
		(fp_rect
			(start -0.508 0.9398)
			(end 0.508 -0.9398)
			(stroke
				(width 0)
				(type default)
			)
			(fill no)
			(layer "F.Fab")
		)
		(pad "1" smd custom
			(at 0 -0.4445 90)
			(size 0.1397 0.1397)
			(layers "F.Cu" "F.Mask" "F.Paste")
			(net "XDP_PCH_TCK1_R")
			(options
				(clearance outline)
				(anchor circle)
			)
			(primitives
				(gr_poly
					(pts
						(arc
							(start -0.1778 -0.2794)
							(mid -0.249642 -0.249642)
							(end -0.2794 -0.1778)
						)
						(arc
							(start -0.2794 0.1778)
							(mid -0.249642 0.249642)
							(end -0.1778 0.2794)
						)
						(arc
							(start 0.1778 0.2794)
							(mid 0.249642 0.249642)
							(end 0.2794 0.1778)
						)
						(arc
							(start 0.2794 -0.1778)
							(mid 0.249642 -0.249642)
							(end 0.1778 -0.2794)
						)
					)
					(width 0)
					(fill yes)
				)
			)
		)
		(pad "2" smd custom
			(at 0 0.4445 90)
			(size 0.1397 0.1397)
			(layers "F.Cu" "F.Mask" "F.Paste")
			(net "XDP_PCH_TCK1")
			(options
				(clearance outline)
				(anchor circle)
			)
			(primitives
				(gr_poly
					(pts
						(arc
							(start -0.1778 -0.2794)
							(mid -0.249642 -0.249642)
							(end -0.2794 -0.1778)
						)
						(arc
							(start -0.2794 0.1778)
							(mid -0.249642 0.249642)
							(end -0.1778 0.2794)
						)
						(arc
							(start 0.1778 0.2794)
							(mid 0.249642 0.249642)
							(end 0.2794 0.1778)
						)
						(arc
							(start 0.2794 -0.1778)
							(mid 0.249642 -0.249642)
							(end 0.1778 -0.2794)
						)
					)
					(width 0)
					(fill yes)
				)
			)
		)
	)
	(footprint ""
		(layer "F.Cu")
		(at 193.4464 -63.25108)
		(property "Reference" "R4E19"
			(at 0 0 0)
			(layer "F.SilkS")
			(hide yes)
			(effects
				(font
					(size 1.27 1.27)
				)
			)
		)
		(property "Value" ""
			(at 0 0 0)
			(layer "F.Fab")
			(effects
				(font
					(size 1.27 1.27)
				)
			)
		)
		(duplicate_pad_numbers_are_jumpers no)
		(fp_poly
			(pts
				(xy -0.2794 -0.1016) (xy 0.2794 -0.1016) (xy 0.2794 0.9906) (xy -0.2794 0.9906)
			)
			(stroke
				(width 0)
				(type default)
			)
			(fill no)
			(layer "F.CrtYd")
		)
		(fp_line
			(start -0.2794 -0.1016)
			(end -0.2794 0.9906)
			(stroke
				(width 0.1)
				(type default)
			)
			(layer "F.Fab")
		)
		(fp_line
			(start -0.2794 0.9906)
			(end 0.2794 0.9906)
			(stroke
				(width 0.1)
				(type default)
			)
			(layer "F.Fab")
		)
		(fp_line
			(start 0.2794 -0.1016)
			(end -0.2794 -0.1016)
			(stroke
				(width 0.1)
				(type default)
			)
			(layer "F.Fab")
		)
		(fp_line
			(start 0.2794 0.9906)
			(end 0.2794 -0.1016)
			(stroke
				(width 0.1)
				(type default)
			)
			(layer "F.Fab")
		)
		(pad "1" smd rect
			(at 0 0)
			(size 0.508 0.508)
			(layers "F.Cu" "F.Mask" "F.Paste")
			(net "VR_PVCCIN_CPU0_PH2_OCSET")
		)
		(pad "2" smd rect
			(at 0 0.889)
			(size 0.508 0.508)
			(layers "F.Cu" "F.Mask" "F.Paste")
			(net "GND")
		)
		(zone
			(layer "F.Cu")
			(hatch none 0.5)
			(connect_pads
				(clearance 0)
			)
			(min_thickness 0.25)
			(keepout
				(tracks allowed)
				(vias not_allowed)
				(pads allowed)
				(copperpour not_allowed)
				(footprints allowed)
			)
			(placement
				(enabled no)
				(sheetname "")
			)
			(fill
				(thermal_gap 0.5)
				(thermal_bridge_width 0.5)
				(island_removal_mode 0)
			)
			(polygon
				(pts
					(xy 193.1924 -62.99708) (xy 193.7004 -62.99708) (xy 193.7004 -62.61608) (xy 193.1924 -62.61608)
				)
			)
		)
		(zone
			(layer "F.Cu")
			(hatch none 0.5)
			(connect_pads
				(clearance 0)
			)
			(min_thickness 0.25)
			(keepout
				(tracks not_allowed)
				(vias allowed)
				(pads allowed)
				(copperpour not_allowed)
				(footprints allowed)
			)
			(placement
				(enabled no)
				(sheetname "")
			)
			(fill
				(thermal_gap 0.5)
				(thermal_bridge_width 0.5)
				(island_removal_mode 0)
			)
			(polygon
				(pts
					(xy 193.1924 -62.61608) (xy 193.7004 -62.61608) (xy 193.7004 -62.99708) (xy 193.1924 -62.99708)
				)
			)
		)
	)
	(footprint ""
		(layer "F.Cu")
		(at 24.05634 -93.323156 180)
		(property "Reference" "RF11"
			(at -0.8382 -0.67818 180)
			(unlocked yes)
			(layer "F.SilkS")
			(effects
				(font
					(size 0.4064 0.254)
					(thickness 0.1524)
				)
				(justify left)
			)
		)
		(property "Value" ""
			(at 0 0 180)
			(layer "F.Fab")
			(effects
				(font
					(size 1.27 1.27)
				)
			)
		)
		(duplicate_pad_numbers_are_jumpers no)
		(fp_poly
			(pts
				(xy -0.2794 -0.1016) (xy 0.2794 -0.1016) (xy 0.2794 0.9906) (xy -0.2794 0.9906)
			)
			(stroke
				(width 0)
				(type default)
			)
			(fill no)
			(layer "F.CrtYd")
		)
		(fp_line
			(start 0.2794 0.9906)
			(end 0.2794 -0.1016)
			(stroke
				(width 0.1)
				(type default)
			)
			(layer "F.Fab")
		)
		(fp_line
			(start 0.2794 -0.1016)
			(end -0.2794 -0.1016)
			(stroke
				(width 0.1)
				(type default)
			)
			(layer "F.Fab")
		)
		(fp_line
			(start -0.2794 0.9906)
			(end 0.2794 0.9906)
			(stroke
				(width 0.1)
				(type default)
			)
			(layer "F.Fab")
		)
		(fp_line
			(start -0.2794 -0.1016)
			(end -0.2794 0.9906)
			(stroke
				(width 0.1)
				(type default)
			)
			(layer "F.Fab")
		)
		(pad "1" smd rect
			(at 0 0 180)
			(size 0.508 0.508)
			(layers "F.Cu" "F.Mask" "F.Paste")
			(net "VR_PVCCIN_CPU1_AIREF5")
		)
		(pad "2" smd rect
			(at 0 0.889 180)
			(size 0.508 0.508)
			(layers "F.Cu" "F.Mask" "F.Paste")
			(net "ISENSE_PVCCIN_CPU1_PH5_IMON")
		)
		(zone
			(layer "F.Cu")
			(hatch none 0.5)
			(connect_pads
				(clearance 0)
			)
			(min_thickness 0.25)
			(keepout
				(tracks not_allowed)
				(vias allowed)
				(pads allowed)
				(copperpour not_allowed)
				(footprints allowed)
			)
			(placement
				(enabled no)
				(sheetname "")
			)
			(fill
				(thermal_gap 0.5)
				(thermal_bridge_width 0.5)
				(island_removal_mode 0)
			)
			(polygon
				(pts
					(xy 24.31034 -93.958156) (xy 23.80234 -93.958156) (xy 23.80234 -93.577156) (xy 24.31034 -93.577156)
				)
			)
		)
		(zone
			(layer "F.Cu")
			(hatch none 0.5)
			(connect_pads
				(clearance 0)
			)
			(min_thickness 0.25)
			(keepout
				(tracks allowed)
				(vias not_allowed)
				(pads allowed)
				(copperpour not_allowed)
				(footprints allowed)
			)
			(placement
				(enabled no)
				(sheetname "")
			)
			(fill
				(thermal_gap 0.5)
				(thermal_bridge_width 0.5)
				(island_removal_mode 0)
			)
			(polygon
				(pts
					(xy 24.31034 -93.577156) (xy 23.80234 -93.577156) (xy 23.80234 -93.958156) (xy 24.31034 -93.958156)
				)
			)
		)
	)
)
